# T6G (Grand Teton) — schematic netlist excerpt (pin names and nets, part order shuffled) for the footprints in the layout excerpt that follows; sources: Cadence DE-HDL packaged netlist, KiCad conversion of 04192023_DAF0TMB3IC0_F0TG_MB_C_brd_V02_OCP.brd

C6736  Q_CAP_DIFFBUS  DIFF BUS_0.22UF 6.3V 20% X6S  pkg C0201  page 352 : \1\ = P5E_CPU1_P3_TX_BUF_C_DN<5> ; \2\ = P5E_CPU1_P3_TX_BUF_DN<5>
R1375  Q_RES  4.7K 5% CHIP  pkg 0201LF  page 185 : A = P1V8_CPU0_RT_1D ; B = SMB_RT_CPU0_P3_ROM_MUX_2D_R_SDA
C2376  Q_CAP  22UF 4V 20% X6S  pkg C0402  page 73 : A = PVDDCR_CPU1_P1 ; B = GND

(kicad_pcb
	(version 20260206)
	(generator "pcbnew")
	(generator_version "10.0")
	(general
		(thickness 1.6)
		(legacy_teardrops no)
	)
	(paper "A4")
	(title_block
		(title "04192023_DAF0TMB3IC0_F0TG_MB_C_brd_V02_OCP.brd")
		(comment 1 "Grand Teton / footprints 6718-6720 of 8354")
	)
	(layers
		(0 "F.Cu" signal "TOP")
		(4 "In1.Cu" signal "GND")
		(6 "In2.Cu" signal "IN1")
		(8 "In3.Cu" signal "GND1")
		(10 "In4.Cu" signal "IN2")
		(12 "In5.Cu" signal "GND2")
		(14 "In6.Cu" signal "IN3")
		(16 "In7.Cu" signal "GND3")
		(18 "In8.Cu" signal "VCC")
		(20 "In9.Cu" signal "VCC1")
		(22 "In10.Cu" signal "GND4")
		(24 "In11.Cu" signal "IN4")
		(26 "In12.Cu" signal "GND5")
		(28 "In13.Cu" signal "IN5")
		(30 "In14.Cu" signal "GND6")
		(32 "In15.Cu" signal "IN6")
		(34 "In16.Cu" signal "GND7")
		(2 "B.Cu" signal "BOTTOM")
		(9 "F.Adhes" user "F.Adhesive")
		(11 "B.Adhes" user "B.Adhesive")
		(13 "F.Paste" user "Package Geometry/Pastemask Top")
		(15 "B.Paste" user "Package Geometry/Pastemask Bottom")
		(5 "F.SilkS" user "Ref Des/Silkscreen Top")
		(7 "B.SilkS" user "Ref Des/Silkscreen Bottom")
		(1 "F.Mask" user "Board Geometry/Soldermask Top")
		(3 "B.Mask" user "Board Geometry/Soldermask Bottom")
		(17 "Dwgs.User" user "User.Drawings")
		(19 "Cmts.User" user "User.Comments")
		(21 "Eco1.User" user "User.Eco1")
		(23 "Eco2.User" user "User.Eco2")
		(25 "Edge.Cuts" user "Board Geometry/Outline")
		(27 "Margin" user)
		(31 "F.CrtYd" user "Package Geometry/Place Bound Top")
		(29 "B.CrtYd" user "Package Geometry/Place Bound Bottom")
		(35 "F.Fab" user "Ref Des/Assembly Top")
		(33 "B.Fab" user "Ref Des/Assembly Bottom")
	)
	(footprint ""
		(layer "B.Cu")
		(at 131.716526 -408.517344 90)
		(property "Reference" "C6736"
			(at 0 0 90)
			(layer "B.SilkS")
			(hide yes)
			(effects
				(font
					(size 1.27 1.27)
				)
				(justify mirror)
			)
		)
		(property "Value" ""
			(at 0 0 90)
			(layer "B.Fab")
			(effects
				(font
					(size 1.27 1.27)
				)
				(justify mirror)
			)
		)
		(duplicate_pad_numbers_are_jumpers no)
		(fp_line
			(start 0.299974 -0.150114)
			(end -0.299974 -0.150114)
			(stroke
				(width 0.1)
				(type default)
			)
			(layer "B.Fab")
		)
		(fp_line
			(start -0.299974 -0.150114)
			(end -0.299974 0.150114)
			(stroke
				(width 0.1)
				(type default)
			)
			(layer "B.Fab")
		)
		(fp_line
			(start 0.299974 0.150114)
			(end 0.299974 -0.150114)
			(stroke
				(width 0.1)
				(type default)
			)
			(layer "B.Fab")
		)
		(fp_line
			(start -0.299974 0.150114)
			(end 0.299974 0.150114)
			(stroke
				(width 0.1)
				(type default)
			)
			(layer "B.Fab")
		)
		(pad "1" smd rect
			(at 0.2667 0 270)
			(size 0.3048 0.381)
			(layers "B.Cu" "B.Mask" "B.Paste")
			(net "P5E_CPU1_P3_TX_BUF_C_DN<5>")
		)
		(pad "2" smd rect
			(at -0.2667 0 270)
			(size 0.3048 0.381)
			(layers "B.Cu" "B.Mask" "B.Paste")
			(net "P5E_CPU1_P3_TX_BUF_DN<5>")
		)
	)
	(footprint ""
		(layer "B.Cu")
		(at 125.468634 -268.855952 60)
		(property "Reference" "C2376"
			(at 0 0 60)
			(layer "B.SilkS")
			(hide yes)
			(effects
				(font
					(size 1.27 1.27)
				)
				(justify mirror)
			)
		)
		(property "Value" ""
			(at 0 0 60)
			(layer "B.Fab")
			(effects
				(font
					(size 1.27 1.27)
				)
				(justify mirror)
			)
		)
		(duplicate_pad_numbers_are_jumpers no)
		(fp_line
			(start -0.787516 -0.406438)
			(end -0.787425 0.40652)
			(stroke
				(width 0.1524)
				(type default)
			)
			(layer "B.SilkS")
		)
		(fp_line
			(start -0.787425 0.40652)
			(end 0.787516 0.406438)
			(stroke
				(width 0.1524)
				(type default)
			)
			(layer "B.SilkS")
		)
		(fp_line
			(start 0.787425 -0.40652)
			(end -0.787516 -0.406438)
			(stroke
				(width 0.1524)
				(type default)
			)
			(layer "B.SilkS")
		)
		(fp_line
			(start 0.787516 0.406438)
			(end 0.787425 -0.40652)
			(stroke
				(width 0.1524)
				(type default)
			)
			(layer "B.SilkS")
		)
		(fp_line
			(start -0.679568 -0.304811)
			(end -0.6795 0.304908)
			(stroke
				(width 0.1)
				(type default)
			)
			(layer "B.Fab")
		)
		(fp_line
			(start -0.120605 -0.304905)
			(end -0.679568 -0.304811)
			(stroke
				(width 0.1)
				(type default)
			)
			(layer "B.Fab")
		)
		(fp_line
			(start -0.120554 -0.279418)
			(end -0.120605 -0.304905)
			(stroke
				(width 0.1)
				(type default)
			)
			(layer "B.Fab")
		)
		(fp_line
			(start 0.120629 -0.30516)
			(end 0.120587 -0.279326)
			(stroke
				(width 0.1)
				(type default)
			)
			(layer "B.Fab")
		)
		(fp_line
			(start 0.120587 -0.279326)
			(end -0.120554 -0.279418)
			(stroke
				(width 0.1)
				(type default)
			)
			(layer "B.Fab")
		)
		(fp_line
			(start -0.6795 0.304908)
			(end -0.120316 0.304686)
			(stroke
				(width 0.1)
				(type default)
			)
			(layer "B.Fab")
		)
		(fp_line
			(start 0.679373 -0.305128)
			(end 0.120629 -0.30516)
			(stroke
				(width 0.1)
				(type default)
			)
			(layer "B.Fab")
		)
		(fp_line
			(start -0.12024 0.279419)
			(end 0.120554 0.279418)
			(stroke
				(width 0.1)
				(type default)
			)
			(layer "B.Fab")
		)
		(fp_line
			(start -0.120316 0.304686)
			(end -0.12024 0.279419)
			(stroke
				(width 0.1)
				(type default)
			)
			(layer "B.Fab")
		)
		(fp_line
			(start 0.120554 0.279418)
			(end 0.120605 0.304905)
			(stroke
				(width 0.1)
				(type default)
			)
			(layer "B.Fab")
		)
		(fp_line
			(start 0.120605 0.304905)
			(end 0.679568 0.304811)
			(stroke
				(width 0.1)
				(type default)
			)
			(layer "B.Fab")
		)
		(fp_line
			(start 0.679568 0.304811)
			(end 0.679373 -0.305128)
			(stroke
				(width 0.1)
				(type default)
			)
			(layer "B.Fab")
		)
		(pad "1" smd circle
			(at 0.40005 0 240)
			(size 0 0)
			(layers "B.Cu" "B.Mask" "B.Paste")
			(net "PVDDCR_CPU1_P1")
		)
		(pad "2" smd circle
			(at -0.40005 0 240)
			(size 0 0)
			(layers "B.Cu" "B.Mask" "B.Paste")
			(net "GND")
		)
	)
	(footprint ""
		(layer "B.Cu")
		(at 254.635 -337.37804 180)
		(property "Reference" "R1375"
			(at 0 0 0)
			(layer "B.SilkS")
			(hide yes)
			(effects
				(font
					(size 1.27 1.27)
				)
				(justify mirror)
			)
		)
		(property "Value" ""
			(at 0 0 0)
			(layer "B.Fab")
			(effects
				(font
					(size 1.27 1.27)
				)
				(justify mirror)
			)
		)
		(duplicate_pad_numbers_are_jumpers no)
		(fp_line
			(start 0.32512 0.175006)
			(end 0.32512 -0.175006)
			(stroke
				(width 0.1)
				(type default)
			)
			(layer "B.Fab")
		)
		(fp_line
			(start 0.32512 -0.175006)
			(end -0.32512 -0.175006)
			(stroke
				(width 0.1)
				(type default)
			)
			(layer "B.Fab")
		)
		(fp_line
			(start -0.32512 0.175006)
			(end 0.32512 0.175006)
			(stroke
				(width 0.1)
				(type default)
			)
			(layer "B.Fab")
		)
		(fp_line
			(start -0.32512 -0.175006)
			(end -0.32512 0.175006)
			(stroke
				(width 0.1)
				(type default)
			)
			(layer "B.Fab")
		)
		(pad "1" smd rect
			(at 0.2667 0)
			(size 0.3048 0.381)
			(layers "B.Cu" "B.Mask" "B.Paste")
			(net "P1V8_CPU0_RT_1D")
		)
		(pad "2" smd rect
			(at -0.2667 0 180)
			(size 0.3048 0.381)
			(layers "B.Cu" "B.Mask" "B.Paste")
			(net "SMB_RT_CPU0_P3_ROM_MUX_2D_R_SDA")
		)
	)
)
